# T6G (Grand Teton) — schematic netlist excerpt (pin names and nets, part order shuffled) for the footprints in the layout excerpt that follows; sources: Cadence DE-HDL packaged netlist, KiCad conversion of 04192023_DAF0TMB3IC0_F0TG_MB_C_brd_V02_OCP.brd

R950  Q_RES  249 1% CHIP  pkg 0402LF  page 166 : A = PU_SMERR_LED ; B = P3V3_AUX
R3664  Q_RES  10K 1% EMPTY  pkg 0402LF  page 234 : A = USB_HUB_PSELF ; B = GND

(kicad_pcb
	(version 20260206)
	(generator "pcbnew")
	(generator_version "10.0")
	(general
		(thickness 1.6)
		(legacy_teardrops no)
	)
	(paper "A4")
	(title_block
		(title "04192023_DAF0TMB3IC0_F0TG_MB_C_brd_V02_OCP.brd")
		(comment 1 "Grand Teton / footprints 4623-4624 of 8354")
	)
	(layers
		(0 "F.Cu" signal "TOP")
		(4 "In1.Cu" signal "GND")
		(6 "In2.Cu" signal "IN1")
		(8 "In3.Cu" signal "GND1")
		(10 "In4.Cu" signal "IN2")
		(12 "In5.Cu" signal "GND2")
		(14 "In6.Cu" signal "IN3")
		(16 "In7.Cu" signal "GND3")
		(18 "In8.Cu" signal "VCC")
		(20 "In9.Cu" signal "VCC1")
		(22 "In10.Cu" signal "GND4")
		(24 "In11.Cu" signal "IN4")
		(26 "In12.Cu" signal "GND5")
		(28 "In13.Cu" signal "IN5")
		(30 "In14.Cu" signal "GND6")
		(32 "In15.Cu" signal "IN6")
		(34 "In16.Cu" signal "GND7")
		(2 "B.Cu" signal "BOTTOM")
		(9 "F.Adhes" user "F.Adhesive")
		(11 "B.Adhes" user "B.Adhesive")
		(13 "F.Paste" user "Package Geometry/Pastemask Top")
		(15 "B.Paste" user "Package Geometry/Pastemask Bottom")
		(5 "F.SilkS" user "Ref Des/Silkscreen Top")
		(7 "B.SilkS" user "Ref Des/Silkscreen Bottom")
		(1 "F.Mask" user "Board Geometry/Soldermask Top")
		(3 "B.Mask" user "Board Geometry/Soldermask Bottom")
		(17 "Dwgs.User" user "User.Drawings")
		(19 "Cmts.User" user "User.Comments")
		(21 "Eco1.User" user "User.Eco1")
		(23 "Eco2.User" user "User.Eco2")
		(25 "Edge.Cuts" user "Board Geometry/Outline")
		(27 "Margin" user)
		(31 "F.CrtYd" user "Package Geometry/Place Bound Top")
		(29 "B.CrtYd" user "Package Geometry/Place Bound Bottom")
		(35 "F.Fab" user "Ref Des/Assembly Top")
		(33 "B.Fab" user "Ref Des/Assembly Bottom")
	)
	(footprint ""
		(layer "F.Cu")
		(at 21.181314 -95.510604)
		(property "Reference" "R3664"
			(at 0 0 0)
			(layer "F.SilkS")
			(hide yes)
			(effects
				(font
					(size 1.27 1.27)
				)
			)
		)
		(property "Value" ""
			(at 0 0 0)
			(layer "F.Fab")
			(effects
				(font
					(size 1.27 1.27)
				)
			)
		)
		(duplicate_pad_numbers_are_jumpers no)
		(fp_line
			(start -0.7874 -0.4064)
			(end 0.7874 -0.4064)
			(stroke
				(width 0.1524)
				(type default)
			)
			(layer "F.SilkS")
		)
		(fp_line
			(start -0.7874 0.4064)
			(end -0.7874 -0.4064)
			(stroke
				(width 0.1524)
				(type default)
			)
			(layer "F.SilkS")
		)
		(fp_line
			(start 0.7874 -0.4064)
			(end 0.7874 0.4064)
			(stroke
				(width 0.1524)
				(type default)
			)
			(layer "F.SilkS")
		)
		(fp_line
			(start 0.7874 0.4064)
			(end -0.7874 0.4064)
			(stroke
				(width 0.1524)
				(type default)
			)
			(layer "F.SilkS")
		)
		(fp_line
			(start -0.67945 -0.305054)
			(end -0.12065 -0.305054)
			(stroke
				(width 0.1)
				(type default)
			)
			(layer "F.Fab")
		)
		(fp_line
			(start -0.67945 0.3048)
			(end -0.67945 -0.305054)
			(stroke
				(width 0.1)
				(type default)
			)
			(layer "F.Fab")
		)
		(fp_line
			(start -0.12065 -0.305054)
			(end -0.12065 -0.2794)
			(stroke
				(width 0.1)
				(type default)
			)
			(layer "F.Fab")
		)
		(fp_line
			(start -0.12065 -0.2794)
			(end 0.12065 -0.2794)
			(stroke
				(width 0.1)
				(type default)
			)
			(layer "F.Fab")
		)
		(fp_line
			(start -0.12065 0.2794)
			(end -0.12065 0.3048)
			(stroke
				(width 0.1)
				(type default)
			)
			(layer "F.Fab")
		)
		(fp_line
			(start -0.12065 0.3048)
			(end -0.67945 0.3048)
			(stroke
				(width 0.1)
				(type default)
			)
			(layer "F.Fab")
		)
		(fp_line
			(start 0.120396 0.2794)
			(end -0.12065 0.2794)
			(stroke
				(width 0.1)
				(type default)
			)
			(layer "F.Fab")
		)
		(fp_line
			(start 0.120396 0.3048)
			(end 0.120396 0.2794)
			(stroke
				(width 0.1)
				(type default)
			)
			(layer "F.Fab")
		)
		(fp_line
			(start 0.12065 -0.3048)
			(end 0.67945 -0.3048)
			(stroke
				(width 0.1)
				(type default)
			)
			(layer "F.Fab")
		)
		(fp_line
			(start 0.12065 -0.2794)
			(end 0.12065 -0.3048)
			(stroke
				(width 0.1)
				(type default)
			)
			(layer "F.Fab")
		)
		(fp_line
			(start 0.67945 -0.3048)
			(end 0.67945 0.3048)
			(stroke
				(width 0.1)
				(type default)
			)
			(layer "F.Fab")
		)
		(fp_line
			(start 0.67945 0.3048)
			(end 0.120396 0.3048)
			(stroke
				(width 0.1)
				(type default)
			)
			(layer "F.Fab")
		)
		(pad "1" smd circle
			(at -0.40005 0)
			(size 0 0)
			(layers "F.Cu" "F.Mask" "F.Paste")
			(net "USB_HUB_PSELF")
		)
		(pad "2" smd circle
			(at 0.40005 0)
			(size 0 0)
			(layers "F.Cu" "F.Mask" "F.Paste")
			(net "GND")
		)
	)
	(footprint ""
		(layer "F.Cu")
		(at 341.33536 -15.979394 90)
		(property "Reference" "R950"
			(at 0 0 90)
			(layer "F.SilkS")
			(hide yes)
			(effects
				(font
					(size 1.27 1.27)
				)
			)
		)
		(property "Value" ""
			(at 0 0 90)
			(layer "F.Fab")
			(effects
				(font
					(size 1.27 1.27)
				)
			)
		)
		(duplicate_pad_numbers_are_jumpers no)
		(fp_line
			(start 0.7874 -0.4064)
			(end 0.7874 0.4064)
			(stroke
				(width 0.1524)
				(type default)
			)
			(layer "F.SilkS")
		)
		(fp_line
			(start -0.7874 -0.4064)
			(end 0.7874 -0.4064)
			(stroke
				(width 0.1524)
				(type default)
			)
			(layer "F.SilkS")
		)
		(fp_line
			(start 0.7874 0.4064)
			(end -0.7874 0.4064)
			(stroke
				(width 0.1524)
				(type default)
			)
			(layer "F.SilkS")
		)
		(fp_line
			(start -0.7874 0.4064)
			(end -0.7874 -0.4064)
			(stroke
				(width 0.1524)
				(type default)
			)
			(layer "F.SilkS")
		)
		(fp_line
			(start -0.12065 -0.305054)
			(end -0.12065 -0.2794)
			(stroke
				(width 0.1)
				(type default)
			)
			(layer "F.Fab")
		)
		(fp_line
			(start -0.67945 -0.305054)
			(end -0.12065 -0.305054)
			(stroke
				(width 0.1)
				(type default)
			)
			(layer "F.Fab")
		)
		(fp_line
			(start 0.67945 -0.3048)
			(end 0.67945 0.3048)
			(stroke
				(width 0.1)
				(type default)
			)
			(layer "F.Fab")
		)
		(fp_line
			(start 0.12065 -0.3048)
			(end 0.67945 -0.3048)
			(stroke
				(width 0.1)
				(type default)
			)
			(layer "F.Fab")
		)
		(fp_line
			(start 0.12065 -0.2794)
			(end 0.12065 -0.3048)
			(stroke
				(width 0.1)
				(type default)
			)
			(layer "F.Fab")
		)
		(fp_line
			(start -0.12065 -0.2794)
			(end 0.12065 -0.2794)
			(stroke
				(width 0.1)
				(type default)
			)
			(layer "F.Fab")
		)
		(fp_line
			(start 0.120396 0.2794)
			(end -0.12065 0.2794)
			(stroke
				(width 0.1)
				(type default)
			)
			(layer "F.Fab")
		)
		(fp_line
			(start -0.12065 0.2794)
			(end -0.12065 0.3048)
			(stroke
				(width 0.1)
				(type default)
			)
			(layer "F.Fab")
		)
		(fp_line
			(start 0.67945 0.3048)
			(end 0.120396 0.3048)
			(stroke
				(width 0.1)
				(type default)
			)
			(layer "F.Fab")
		)
		(fp_line
			(start 0.120396 0.3048)
			(end 0.120396 0.2794)
			(stroke
				(width 0.1)
				(type default)
			)
			(layer "F.Fab")
		)
		(fp_line
			(start -0.12065 0.3048)
			(end -0.67945 0.3048)
			(stroke
				(width 0.1)
				(type default)
			)
			(layer "F.Fab")
		)
		(fp_line
			(start -0.67945 0.3048)
			(end -0.67945 -0.305054)
			(stroke
				(width 0.1)
				(type default)
			)
			(layer "F.Fab")
		)
		(pad "1" smd circle
			(at -0.40005 0 90)
			(size 0 0)
			(layers "F.Cu" "F.Mask" "F.Paste")
			(net "PU_SMERR_LED")
		)
		(pad "2" smd circle
			(at 0.40005 0 90)
			(size 0 0)
			(layers "F.Cu" "F.Mask" "F.Paste")
			(net "P3V3_AUX")
		)
	)
)
